(kicad_pcb
	(version 20260206)
	(generator "pcbnew")
	(generator_version "10.0")
	(general
		(thickness 1.6)
		(legacy_teardrops no)
	)
	(paper "A4")
	(title_block
		(title "peb — Lightning_PEB_BRD.brd")
		(comment 1 "Lightning (Wiwynn / Facebook NVMe JBOF) / footprints 1911-1918 of 2563")
	)
	(layers
		(0 "F.Cu" signal "TOP")
		(4 "In1.Cu" signal "L2GND")
		(6 "In2.Cu" signal "L3")
		(8 "In3.Cu" signal "L4VCC")
		(10 "In4.Cu" signal "L5VCC")
		(12 "In5.Cu" signal "L6")
		(14 "In6.Cu" signal "L7GND")
		(2 "B.Cu" signal "BOTTOM")
		(9 "F.Adhes" user "F.Adhesive")
		(11 "B.Adhes" user "B.Adhesive")
		(13 "F.Paste" user "Package Geometry/Pastemask Top")
		(15 "B.Paste" user "Package Geometry/Pastemask Bottom")
		(5 "F.SilkS" user "Ref Des/Silkscreen Top")
		(7 "B.SilkS" user "Ref Des/Silkscreen Bottom")
		(1 "F.Mask" user "Board Geometry/Soldermask Top")
		(3 "B.Mask" user "Board Geometry/Soldermask Bottom")
		(17 "Dwgs.User" user "User.Drawings")
		(19 "Cmts.User" user "User.Comments")
		(21 "Eco1.User" user "User.Eco1")
		(23 "Eco2.User" user "User.Eco2")
		(25 "Edge.Cuts" user "Board Geometry/Outline")
		(27 "Margin" user)
		(31 "F.CrtYd" user "Package Geometry/Place Bound Top")
		(29 "B.CrtYd" user "Package Geometry/Place Bound Bottom")
		(35 "F.Fab" user "Ref Des/Assembly Top")
		(33 "B.Fab" user "Ref Des/Assembly Bottom")
	)
	(footprint ""
		(layer "B.Cu")
		(at 66.938652 -122.3264 -90)
		(property "Reference" "R262"
			(at 0 0 90)
			(layer "B.SilkS")
			(hide yes)
			(effects
				(font
					(size 1.27 1.27)
				)
				(justify mirror)
			)
		)
		(property "Value" "0R2J-2-GP"
			(at -0.064008 -3.993896 270)
			(unlocked yes)
			(layer "B.Fab")
			(hide yes)
			(effects
				(font
					(size 1.016 1.016)
					(thickness 0.1524)
				)
				(justify mirror)
			)
		)
		(property "Device Type" "R402H16"
			(at -0.064008 -5.517896 270)
			(unlocked yes)
			(layer "B.Fab")
			(hide yes)
			(effects
				(font
					(size 1.016 1.016)
					(thickness 0.1524)
				)
				(justify mirror)
			)
		)
		(duplicate_pad_numbers_are_jumpers no)
		(fp_line
			(start -0.508 -0.9398)
			(end 0.508 -0.9398)
			(stroke
				(width 0.1524)
				(type default)
			)
			(layer "B.SilkS")
		)
		(fp_line
			(start 0.508 -0.9398)
			(end 0.508 0.9398)
			(stroke
				(width 0.1524)
				(type default)
			)
			(layer "B.SilkS")
		)
		(fp_rect
			(start 0.508 0.9398)
			(end -0.508 -0.9398)
			(stroke
				(width 0)
				(type default)
			)
			(fill no)
			(layer "B.CrtYd")
		)
		(fp_rect
			(start 0.508 0.9398)
			(end -0.508 -0.9398)
			(stroke
				(width 0)
				(type default)
			)
			(fill no)
			(layer "B.Fab")
		)
		(pad "1" smd custom
			(at 0 -0.4445 90)
			(size 0.1397 0.1397)
			(layers "B.Cu" "B.Mask" "B.Paste")
			(net "LAN_SMB_DAT")
			(options
				(clearance outline)
				(anchor circle)
			)
			(primitives
				(gr_poly
					(pts
						(arc
							(start -0.1778 0.2794)
							(mid -0.249642 0.249642)
							(end -0.2794 0.1778)
						)
						(arc
							(start -0.2794 -0.1778)
							(mid -0.249642 -0.249642)
							(end -0.1778 -0.2794)
						)
						(arc
							(start 0.1778 -0.2794)
							(mid 0.249642 -0.249642)
							(end 0.2794 -0.1778)
						)
						(arc
							(start 0.2794 0.1778)
							(mid 0.249642 0.249642)
							(end 0.1778 0.2794)
						)
					)
					(width 0)
					(fill yes)
				)
			)
		)
		(pad "2" smd custom
			(at 0 0.4445 90)
			(size 0.1397 0.1397)
			(layers "B.Cu" "B.Mask" "B.Paste")
			(net "BMC0_SMB4_DAT")
			(options
				(clearance outline)
				(anchor circle)
			)
			(primitives
				(gr_poly
					(pts
						(arc
							(start -0.1778 0.2794)
							(mid -0.249642 0.249642)
							(end -0.2794 0.1778)
						)
						(arc
							(start -0.2794 -0.1778)
							(mid -0.249642 -0.249642)
							(end -0.1778 -0.2794)
						)
						(arc
							(start 0.1778 -0.2794)
							(mid 0.249642 -0.249642)
							(end 0.2794 -0.1778)
						)
						(arc
							(start 0.2794 0.1778)
							(mid 0.249642 0.249642)
							(end 0.1778 0.2794)
						)
					)
					(width 0)
					(fill yes)
				)
			)
		)
	)
	(footprint ""
		(layer "B.Cu")
		(at 74.803 -37.465)
		(property "Reference" "PC30"
			(at 0 0 0)
			(layer "B.SilkS")
			(hide yes)
			(effects
				(font
					(size 1.27 1.27)
				)
				(justify mirror)
			)
		)
		(property "Value" "SCD1U25V2KX-2-GP"
			(at -1.1811 -2.7051 0)
			(unlocked yes)
			(layer "B.Fab")
			(hide yes)
			(effects
				(font
					(size 1.016 1.016)
					(thickness 0.1524)
				)
				(justify mirror)
			)
		)
		(property "Device Type" "C402H22"
			(at -1.1811 -4.2291 0)
			(unlocked yes)
			(layer "B.Fab")
			(hide yes)
			(effects
				(font
					(size 1.016 1.016)
					(thickness 0.1524)
				)
				(justify mirror)
			)
		)
		(duplicate_pad_numbers_are_jumpers no)
		(fp_rect
			(start 0.4318 0.9525)
			(end -0.4318 -0.9525)
			(stroke
				(width 0)
				(type default)
			)
			(fill no)
			(layer "B.CrtYd")
		)
		(fp_rect
			(start 0.4318 0.9525)
			(end -0.4318 -0.9525)
			(stroke
				(width 0)
				(type default)
			)
			(fill no)
			(layer "B.Fab")
		)
		(pad "1" smd custom
			(at 0 -0.4445 180)
			(size 0.1524 0.1524)
			(layers "B.Cu" "B.Mask" "B.Paste")
			(net "P3V3_PWR")
			(options
				(clearance outline)
				(anchor circle)
			)
			(primitives
				(gr_poly
					(pts
						(arc
							(start 0.3048 0.2032)
							(mid 0.275042 0.275042)
							(end 0.2032 0.3048)
						)
						(arc
							(start -0.2032 0.3048)
							(mid -0.275042 0.275042)
							(end -0.3048 0.2032)
						)
						(arc
							(start -0.3048 -0.2032)
							(mid -0.275042 -0.275042)
							(end -0.2032 -0.3048)
						)
						(arc
							(start 0.2032 -0.3048)
							(mid 0.275042 -0.275042)
							(end 0.3048 -0.2032)
						)
					)
					(width 0)
					(fill yes)
				)
			)
		)
		(pad "2" smd custom
			(at 0 0.4445 180)
			(size 0.1524 0.1524)
			(layers "B.Cu" "B.Mask" "B.Paste")
			(net "P3V3_STBY_LL_R")
			(options
				(clearance outline)
				(anchor circle)
			)
			(primitives
				(gr_poly
					(pts
						(arc
							(start 0.3048 0.2032)
							(mid 0.275042 0.275042)
							(end 0.2032 0.3048)
						)
						(arc
							(start -0.2032 0.3048)
							(mid -0.275042 0.275042)
							(end -0.3048 0.2032)
						)
						(arc
							(start -0.3048 -0.2032)
							(mid -0.275042 -0.275042)
							(end -0.2032 -0.3048)
						)
						(arc
							(start 0.2032 -0.3048)
							(mid 0.275042 -0.275042)
							(end 0.3048 -0.2032)
						)
					)
					(width 0)
					(fill yes)
				)
			)
		)
	)
	(footprint ""
		(layer "B.Cu")
		(at 21.837904 -73.989692 -90)
		(property "Reference" "C634"
			(at 0 0 90)
			(layer "B.SilkS")
			(hide yes)
			(effects
				(font
					(size 1.27 1.27)
				)
				(justify mirror)
			)
		)
		(property "Value" "SC10U6D3V5KX-4GP"
			(at 0.0762 -6.1214 270)
			(unlocked yes)
			(layer "B.Fab")
			(hide yes)
			(effects
				(font
					(size 1.016 1.016)
					(thickness 0.1524)
				)
				(justify mirror)
			)
		)
		(property "Device Type" "C805H58"
			(at 0.0762 -8.1534 270)
			(unlocked yes)
			(layer "B.Fab")
			(hide yes)
			(effects
				(font
					(size 1.016 1.016)
					(thickness 0.1524)
				)
				(justify mirror)
			)
		)
		(duplicate_pad_numbers_are_jumpers no)
		(fp_line
			(start -0.635 0)
			(end 0.635 0)
			(stroke
				(width 0.508)
				(type default)
			)
			(layer "B.SilkS")
		)
		(fp_rect
			(start 0.9652 1.778)
			(end -0.9652 -1.778)
			(stroke
				(width 0)
				(type default)
			)
			(fill no)
			(layer "B.CrtYd")
		)
		(fp_poly
			(pts
				(xy 0.9652 -1.778) (xy -0.9652 -1.778) (xy -0.9652 1.778) (xy 0.9652 1.778)
			)
			(stroke
				(width 0)
				(type default)
			)
			(fill no)
			(layer "B.Fab")
		)
		(pad "1" smd rect
			(at 0 -0.9652 90)
			(size 1.397 1.143)
			(layers "B.Cu" "B.Mask" "B.Paste")
			(net "P0V9_I210")
		)
		(pad "2" smd rect
			(at 0 0.9652 90)
			(size 1.397 1.143)
			(layers "B.Cu" "B.Mask" "B.Paste")
			(net "GND")
		)
	)
	(footprint ""
		(layer "B.Cu")
		(at 145.88363 -33.53562)
		(property "Reference" "R2919"
			(at 0 0 0)
			(layer "B.SilkS")
			(hide yes)
			(effects
				(font
					(size 1.27 1.27)
				)
				(justify mirror)
			)
		)
		(property "Value" "0R2J-2-GP"
			(at -0.064008 -3.993896 0)
			(unlocked yes)
			(layer "B.Fab")
			(hide yes)
			(effects
				(font
					(size 1.016 1.016)
					(thickness 0.1524)
				)
				(justify mirror)
			)
		)
		(property "Device Type" "R402H16"
			(at -0.064008 -5.517896 0)
			(unlocked yes)
			(layer "B.Fab")
			(hide yes)
			(effects
				(font
					(size 1.016 1.016)
					(thickness 0.1524)
				)
				(justify mirror)
			)
		)
		(duplicate_pad_numbers_are_jumpers no)
		(fp_line
			(start -0.508 -0.9398)
			(end 0.508 -0.9398)
			(stroke
				(width 0.1524)
				(type default)
			)
			(layer "B.SilkS")
		)
		(fp_line
			(start 0.508 -0.9398)
			(end 0.508 0.9398)
			(stroke
				(width 0.1524)
				(type default)
			)
			(layer "B.SilkS")
		)
		(fp_rect
			(start 0.508 0.9398)
			(end -0.508 -0.9398)
			(stroke
				(width 0)
				(type default)
			)
			(fill no)
			(layer "B.CrtYd")
		)
		(fp_rect
			(start 0.508 0.9398)
			(end -0.508 -0.9398)
			(stroke
				(width 0)
				(type default)
			)
			(fill no)
			(layer "B.Fab")
		)
		(pad "1" smd custom
			(at 0 -0.4445 180)
			(size 0.1397 0.1397)
			(layers "B.Cu" "B.Mask" "B.Paste")
			(net "BMC_I2C2_MINI2_SDA")
			(options
				(clearance outline)
				(anchor circle)
			)
			(primitives
				(gr_poly
					(pts
						(arc
							(start -0.1778 0.2794)
							(mid -0.249642 0.249642)
							(end -0.2794 0.1778)
						)
						(arc
							(start -0.2794 -0.1778)
							(mid -0.249642 -0.249642)
							(end -0.1778 -0.2794)
						)
						(arc
							(start 0.1778 -0.2794)
							(mid 0.249642 -0.249642)
							(end 0.2794 -0.1778)
						)
						(arc
							(start 0.2794 0.1778)
							(mid 0.249642 0.249642)
							(end 0.1778 0.2794)
						)
					)
					(width 0)
					(fill yes)
				)
			)
		)
		(pad "2" smd custom
			(at 0 0.4445 180)
			(size 0.1397 0.1397)
			(layers "B.Cu" "B.Mask" "B.Paste")
			(net "8644_SDA_R_2")
			(options
				(clearance outline)
				(anchor circle)
			)
			(primitives
				(gr_poly
					(pts
						(arc
							(start -0.1778 0.2794)
							(mid -0.249642 0.249642)
							(end -0.2794 0.1778)
						)
						(arc
							(start -0.2794 -0.1778)
							(mid -0.249642 -0.249642)
							(end -0.1778 -0.2794)
						)
						(arc
							(start 0.1778 -0.2794)
							(mid 0.249642 -0.249642)
							(end 0.2794 -0.1778)
						)
						(arc
							(start 0.2794 0.1778)
							(mid 0.249642 0.249642)
							(end 0.1778 0.2794)
						)
					)
					(width 0)
					(fill yes)
				)
			)
		)
	)
	(footprint ""
		(layer "B.Cu")
		(at 156.470604 -33.592008)
		(property "Reference" "R2923"
			(at 0 0 0)
			(layer "B.SilkS")
			(hide yes)
			(effects
				(font
					(size 1.27 1.27)
				)
				(justify mirror)
			)
		)
		(property "Value" "0R2J-2-GP"
			(at -0.064008 -3.993896 0)
			(unlocked yes)
			(layer "B.Fab")
			(hide yes)
			(effects
				(font
					(size 1.016 1.016)
					(thickness 0.1524)
				)
				(justify mirror)
			)
		)
		(property "Device Type" "R402H16"
			(at -0.064008 -5.517896 0)
			(unlocked yes)
			(layer "B.Fab")
			(hide yes)
			(effects
				(font
					(size 1.016 1.016)
					(thickness 0.1524)
				)
				(justify mirror)
			)
		)
		(duplicate_pad_numbers_are_jumpers no)
		(fp_line
			(start -0.508 -0.9398)
			(end 0.508 -0.9398)
			(stroke
				(width 0.1524)
				(type default)
			)
			(layer "B.SilkS")
		)
		(fp_line
			(start 0.508 -0.9398)
			(end 0.508 0.9398)
			(stroke
				(width 0.1524)
				(type default)
			)
			(layer "B.SilkS")
		)
		(fp_rect
			(start 0.508 0.9398)
			(end -0.508 -0.9398)
			(stroke
				(width 0)
				(type default)
			)
			(fill no)
			(layer "B.CrtYd")
		)
		(fp_rect
			(start 0.508 0.9398)
			(end -0.508 -0.9398)
			(stroke
				(width 0)
				(type default)
			)
			(fill no)
			(layer "B.Fab")
		)
		(pad "1" smd custom
			(at 0 -0.4445 180)
			(size 0.1397 0.1397)
			(layers "B.Cu" "B.Mask" "B.Paste")
			(net "BMC_I2C3_MINI3_SDA")
			(options
				(clearance outline)
				(anchor circle)
			)
			(primitives
				(gr_poly
					(pts
						(arc
							(start -0.1778 0.2794)
							(mid -0.249642 0.249642)
							(end -0.2794 0.1778)
						)
						(arc
							(start -0.2794 -0.1778)
							(mid -0.249642 -0.249642)
							(end -0.1778 -0.2794)
						)
						(arc
							(start 0.1778 -0.2794)
							(mid 0.249642 -0.249642)
							(end 0.2794 -0.1778)
						)
						(arc
							(start 0.2794 0.1778)
							(mid 0.249642 0.249642)
							(end 0.1778 0.2794)
						)
					)
					(width 0)
					(fill yes)
				)
			)
		)
		(pad "2" smd custom
			(at 0 0.4445 180)
			(size 0.1397 0.1397)
			(layers "B.Cu" "B.Mask" "B.Paste")
			(net "8644_SDA_R_3")
			(options
				(clearance outline)
				(anchor circle)
			)
			(primitives
				(gr_poly
					(pts
						(arc
							(start -0.1778 0.2794)
							(mid -0.249642 0.249642)
							(end -0.2794 0.1778)
						)
						(arc
							(start -0.2794 -0.1778)
							(mid -0.249642 -0.249642)
							(end -0.1778 -0.2794)
						)
						(arc
							(start 0.1778 -0.2794)
							(mid 0.249642 -0.249642)
							(end 0.2794 -0.1778)
						)
						(arc
							(start 0.2794 0.1778)
							(mid 0.249642 0.249642)
							(end 0.1778 0.2794)
						)
					)
					(width 0)
					(fill yes)
				)
			)
		)
	)
	(footprint ""
		(layer "B.Cu")
		(at 216.5096 -194.0306)
		(property "Reference" "R3242"
			(at 0 0 0)
			(layer "B.SilkS")
			(hide yes)
			(effects
				(font
					(size 1.27 1.27)
				)
				(justify mirror)
			)
		)
		(property "Value" "0R2J-2-GP"
			(at -0.064008 -3.993896 0)
			(unlocked yes)
			(layer "B.Fab")
			(hide yes)
			(effects
				(font
					(size 1.016 1.016)
					(thickness 0.1524)
				)
				(justify mirror)
			)
		)
		(property "Device Type" "R402H16"
			(at -0.064008 -5.517896 0)
			(unlocked yes)
			(layer "B.Fab")
			(hide yes)
			(effects
				(font
					(size 1.016 1.016)
					(thickness 0.1524)
				)
				(justify mirror)
			)
		)
		(duplicate_pad_numbers_are_jumpers no)
		(fp_line
			(start -0.508 -0.9398)
			(end 0.508 -0.9398)
			(stroke
				(width 0.1524)
				(type default)
			)
			(layer "B.SilkS")
		)
		(fp_line
			(start 0.508 -0.9398)
			(end 0.508 0.9398)
			(stroke
				(width 0.1524)
				(type default)
			)
			(layer "B.SilkS")
		)
		(fp_rect
			(start 0.508 0.9398)
			(end -0.508 -0.9398)
			(stroke
				(width 0)
				(type default)
			)
			(fill no)
			(layer "B.CrtYd")
		)
		(fp_rect
			(start 0.508 0.9398)
			(end -0.508 -0.9398)
			(stroke
				(width 0)
				(type default)
			)
			(fill no)
			(layer "B.Fab")
		)
		(pad "1" smd custom
			(at 0 -0.4445 180)
			(size 0.1397 0.1397)
			(layers "B.Cu" "B.Mask" "B.Paste")
			(net "SSD_PERST_Y13")
			(options
				(clearance outline)
				(anchor circle)
			)
			(primitives
				(gr_poly
					(pts
						(arc
							(start -0.1778 0.2794)
							(mid -0.249642 0.249642)
							(end -0.2794 0.1778)
						)
						(arc
							(start -0.2794 -0.1778)
							(mid -0.249642 -0.249642)
							(end -0.1778 -0.2794)
						)
						(arc
							(start 0.1778 -0.2794)
							(mid 0.249642 -0.249642)
							(end 0.2794 -0.1778)
						)
						(arc
							(start 0.2794 0.1778)
							(mid 0.249642 0.249642)
							(end 0.1778 0.2794)
						)
					)
					(width 0)
					(fill yes)
				)
			)
		)
		(pad "2" smd custom
			(at 0 0.4445 180)
			(size 0.1397 0.1397)
			(layers "B.Cu" "B.Mask" "B.Paste")
			(net "SSD_PERST#13_R")
			(options
				(clearance outline)
				(anchor circle)
			)
			(primitives
				(gr_poly
					(pts
						(arc
							(start -0.1778 0.2794)
							(mid -0.249642 0.249642)
							(end -0.2794 0.1778)
						)
						(arc
							(start -0.2794 -0.1778)
							(mid -0.249642 -0.249642)
							(end -0.1778 -0.2794)
						)
						(arc
							(start 0.1778 -0.2794)
							(mid 0.249642 -0.249642)
							(end 0.2794 -0.1778)
						)
						(arc
							(start 0.2794 0.1778)
							(mid 0.249642 0.249642)
							(end 0.1778 0.2794)
						)
					)
					(width 0)
					(fill yes)
				)
			)
		)
	)
	(footprint ""
		(layer "B.Cu")
		(at 227.6856 -40.004746 -90)
		(property "Reference" "C556"
			(at 0 0 90)
			(layer "B.SilkS")
			(hide yes)
			(effects
				(font
					(size 1.27 1.27)
				)
				(justify mirror)
			)
		)
		(property "Value" "SCD1U16V1KX-1-GP"
			(at 2.8321 -1.7399 270)
			(unlocked yes)
			(layer "B.Fab")
			(hide yes)
			(effects
				(font
					(size 1.016 1.016)
					(thickness 0.1524)
				)
				(justify mirror)
			)
		)
		(property "Device Type" "C0201H13"
			(at 2.8321 -3.2639 270)
			(unlocked yes)
			(layer "B.Fab")
			(hide yes)
			(effects
				(font
					(size 1.016 1.016)
					(thickness 0.1524)
				)
				(justify mirror)
			)
		)
		(duplicate_pad_numbers_are_jumpers no)
		(fp_rect
			(start 0.2794 0.6477)
			(end -0.2794 -0.6477)
			(stroke
				(width 0)
				(type default)
			)
			(fill no)
			(layer "B.CrtYd")
		)
		(fp_rect
			(start 0.2794 0.6477)
			(end -0.2794 -0.6477)
			(stroke
				(width 0)
				(type default)
			)
			(fill no)
			(layer "B.Fab")
		)
		(pad "1" smd custom
			(at 0 -0.2794 90)
			(size 0.0762 0.0762)
			(layers "B.Cu" "B.Mask" "B.Paste")
			(net "DUT_AVD_PCIE")
			(options
				(clearance outline)
				(anchor circle)
			)
			(primitives
				(gr_poly
					(pts
						(arc
							(start 0.1524 0.127)
							(mid 0.137521 0.162921)
							(end 0.1016 0.1778)
						)
						(arc
							(start -0.1016 0.1778)
							(mid -0.137521 0.162921)
							(end -0.1524 0.127)
						)
						(arc
							(start -0.1524 -0.127)
							(mid -0.137521 -0.162921)
							(end -0.1016 -0.1778)
						)
						(arc
							(start 0.1016 -0.1778)
							(mid 0.137521 -0.162921)
							(end 0.1524 -0.127)
						)
					)
					(width 0)
					(fill yes)
				)
			)
		)
		(pad "2" smd custom
			(at 0 0.2794 90)
			(size 0.0762 0.0762)
			(layers "B.Cu" "B.Mask" "B.Paste")
			(net "GND")
			(options
				(clearance outline)
				(anchor circle)
			)
			(primitives
				(gr_poly
					(pts
						(arc
							(start 0.1524 0.127)
							(mid 0.137521 0.162921)
							(end 0.1016 0.1778)
						)
						(arc
							(start -0.1016 0.1778)
							(mid -0.137521 0.162921)
							(end -0.1524 0.127)
						)
						(arc
							(start -0.1524 -0.127)
							(mid -0.137521 -0.162921)
							(end -0.1016 -0.1778)
						)
						(arc
							(start 0.1016 -0.1778)
							(mid 0.137521 -0.162921)
							(end 0.1524 -0.127)
						)
					)
					(width 0)
					(fill yes)
				)
			)
		)
	)
	(footprint ""
		(layer "B.Cu")
		(at 346.329 -67.056 180)
		(property "Reference" "PC184"
			(at 0 0 0)
			(layer "B.SilkS")
			(hide yes)
			(effects
				(font
					(size 1.27 1.27)
				)
				(justify mirror)
			)
		)
		(property "Value" "SC4D7U25V5KX-1-GP"
			(at 0.0762 -6.1214 180)
			(unlocked yes)
			(layer "B.Fab")
			(hide yes)
			(effects
				(font
					(size 1.016 1.016)
					(thickness 0.1524)
				)
				(justify mirror)
			)
		)
		(property "Device Type" "C805H58"
			(at 0.0762 -8.1534 180)
			(unlocked yes)
			(layer "B.Fab")
			(hide yes)
			(effects
				(font
					(size 1.016 1.016)
					(thickness 0.1524)
				)
				(justify mirror)
			)
		)
		(duplicate_pad_numbers_are_jumpers no)
		(fp_line
			(start -0.635 0)
			(end 0.635 0)
			(stroke
				(width 0.508)
				(type default)
			)
			(layer "B.SilkS")
		)
		(fp_rect
			(start 0.9652 1.778)
			(end -0.9652 -1.778)
			(stroke
				(width 0)
				(type default)
			)
			(fill no)
			(layer "B.CrtYd")
		)
		(fp_poly
			(pts
				(xy 0.9652 -1.778) (xy -0.9652 -1.778) (xy -0.9652 1.778) (xy 0.9652 1.778)
			)
			(stroke
				(width 0)
				(type default)
			)
			(fill no)
			(layer "B.Fab")
		)
		(pad "1" smd rect
			(at 0 -0.9652)
			(size 1.397 1.143)
			(layers "B.Cu" "B.Mask" "B.Paste")
			(net "P0V9_E_VDD")
		)
		(pad "2" smd rect
			(at 0 0.9652)
			(size 1.397 1.143)
			(layers "B.Cu" "B.Mask" "B.Paste")
			(net "GND")
		)
	)
)
